(kicad_pcb
	(version 20260206)
	(generator "pcbnew")
	(generator_version "10.0")
	(general
		(thickness 1.6)
		(legacy_teardrops no)
	)
	(paper "A4")
	(title_block
		(title "baseboard — 13948-1b.1110WZS1818.brd")
		(comment 1 "Honey Badger (Wiwynn) / footprints 162-167 of 2523")
	)
	(layers
		(0 "F.Cu" signal "TOP")
		(4 "In1.Cu" signal "L2GND")
		(6 "In2.Cu" signal "L3")
		(8 "In3.Cu" signal "L4VCC")
		(10 "In4.Cu" signal "L5VCC")
		(12 "In5.Cu" signal "L6")
		(14 "In6.Cu" signal "L7GND")
		(2 "B.Cu" signal "BOTTOM")
		(9 "F.Adhes" user "F.Adhesive")
		(11 "B.Adhes" user "B.Adhesive")
		(13 "F.Paste" user "Package Geometry/Pastemask Top")
		(15 "B.Paste" user "Package Geometry/Pastemask Bottom")
		(5 "F.SilkS" user "Ref Des/Silkscreen Top")
		(7 "B.SilkS" user "Ref Des/Silkscreen Bottom")
		(1 "F.Mask" user "Board Geometry/Soldermask Top")
		(3 "B.Mask" user "Board Geometry/Soldermask Bottom")
		(17 "Dwgs.User" user "User.Drawings")
		(19 "Cmts.User" user "User.Comments")
		(21 "Eco1.User" user "User.Eco1")
		(23 "Eco2.User" user "User.Eco2")
		(25 "Edge.Cuts" user "Board Geometry/Outline")
		(27 "Margin" user)
		(31 "F.CrtYd" user "Package Geometry/Place Bound Top")
		(29 "B.CrtYd" user "Package Geometry/Place Bound Bottom")
		(35 "F.Fab" user "Ref Des/Assembly Top")
		(33 "B.Fab" user "Ref Des/Assembly Bottom")
	)
	(footprint ""
		(layer "F.Cu")
		(at 14.99108 -231.568752)
		(property "Reference" "SU15"
			(at 0 0 0)
			(layer "F.SilkS")
			(hide yes)
			(effects
				(font
					(size 1.27 1.27)
				)
			)
		)
		(property "Value" "PI3C3861-AQE-GP"
			(at 0 -13.1572 0)
			(unlocked yes)
			(layer "F.Fab")
			(hide yes)
			(effects
				(font
					(size 1.016 1.016)
					(thickness 0.1524)
				)
			)
		)
		(property "Device Type" "QSOIC24H69"
			(at 0 -15.1892 0)
			(unlocked yes)
			(layer "F.Fab")
			(hide yes)
			(effects
				(font
					(size 1.016 1.016)
					(thickness 0.1524)
				)
			)
		)
		(duplicate_pad_numbers_are_jumpers no)
		(fp_line
			(start -4.4958 -1.5748)
			(end 3.5814 -1.5748)
			(stroke
				(width 0.1524)
				(type default)
			)
			(layer "F.SilkS")
		)
		(fp_line
			(start -4.4958 -0.4318)
			(end -4.4958 -1.5748)
			(stroke
				(width 0.1524)
				(type default)
			)
			(layer "F.SilkS")
		)
		(fp_line
			(start -4.4958 -0.4318)
			(end -4.064 0)
			(stroke
				(width 0.1524)
				(type default)
			)
			(layer "F.SilkS")
		)
		(fp_line
			(start -4.4958 0.4318)
			(end -4.4958 -0.4318)
			(stroke
				(width 0.1524)
				(type default)
			)
			(layer "F.SilkS")
		)
		(fp_line
			(start -4.4958 0.4318)
			(end -4.4958 1.5748)
			(stroke
				(width 0.1524)
				(type default)
			)
			(layer "F.SilkS")
		)
		(fp_line
			(start -4.318 1.5748)
			(end -4.318 3.556)
			(stroke
				(width 0.508)
				(type default)
			)
			(layer "F.SilkS")
		)
		(fp_line
			(start -4.064 0)
			(end -4.4958 0.4318)
			(stroke
				(width 0.1524)
				(type default)
			)
			(layer "F.SilkS")
		)
		(fp_line
			(start 3.5814 -1.5748)
			(end 3.5814 1.5748)
			(stroke
				(width 0.1524)
				(type default)
			)
			(layer "F.SilkS")
		)
		(fp_line
			(start 3.5814 1.5748)
			(end -4.4958 1.5748)
			(stroke
				(width 0.1524)
				(type default)
			)
			(layer "F.SilkS")
		)
		(fp_line
			(start 3.5814 1.5748)
			(end 3.5814 -1.5748)
			(stroke
				(width 0.1524)
				(type default)
			)
			(layer "F.SilkS")
		)
		(fp_poly
			(pts
				(xy -3.683 -1.5748) (xy 3.5814 -1.5748) (xy 3.5814 1.5748) (xy -3.683 1.5748)
			)
			(stroke
				(width 0)
				(type default)
			)
			(fill yes)
			(layer "F.SilkS")
		)
		(fp_rect
			(start -4.572 3.81)
			(end 4.572 -3.81)
			(stroke
				(width 0)
				(type default)
			)
			(fill no)
			(layer "F.CrtYd")
		)
		(fp_poly
			(pts
				(xy -4.572 -3.81) (xy 4.572 -3.81) (xy 4.572 3.81) (xy -4.572 3.81)
			)
			(stroke
				(width 0)
				(type default)
			)
			(fill no)
			(layer "F.Fab")
		)
		(pad "1" smd rect
			(at -3.4925 2.6162)
			(size 0.3556 1.524)
			(layers "F.Cu" "F.Mask" "F.Paste")
			(net "Net_1511")
		)
		(pad "2" smd rect
			(at -2.8575 2.6162)
			(size 0.3556 1.524)
			(layers "F.Cu" "F.Mask" "F.Paste")
			(net "SAS_HDD_PWR10")
		)
		(pad "3" smd rect
			(at -2.2225 2.6162)
			(size 0.3556 1.524)
			(layers "F.Cu" "F.Mask" "F.Paste")
			(net "SAS_HDD_PWR11")
		)
		(pad "4" smd rect
			(at -1.5875 2.6162)
			(size 0.3556 1.524)
			(layers "F.Cu" "F.Mask" "F.Paste")
			(net "SAS_HDD_PWR12")
		)
		(pad "5" smd rect
			(at -0.9525 2.6162)
			(size 0.3556 1.524)
			(layers "F.Cu" "F.Mask" "F.Paste")
			(net "SAS_HDD_PWR13")
		)
		(pad "6" smd rect
			(at -0.3175 2.6162)
			(size 0.3556 1.524)
			(layers "F.Cu" "F.Mask" "F.Paste")
			(net "SAS_HDD_PWR14")
		)
		(pad "7" smd rect
			(at 0.3175 2.6162)
			(size 0.3556 1.524)
			(layers "F.Cu" "F.Mask" "F.Paste")
			(net "SAS_HDD_PWR15")
		)
		(pad "8" smd rect
			(at 0.9525 2.6162)
			(size 0.3556 1.524)
			(layers "F.Cu" "F.Mask" "F.Paste")
			(net "Net_1509")
		)
		(pad "9" smd rect
			(at 1.5875 2.6162)
			(size 0.3556 1.524)
			(layers "F.Cu" "F.Mask" "F.Paste")
			(net "Net_1510")
		)
		(pad "10" smd rect
			(at 2.2225 2.6162)
			(size 0.3556 1.524)
			(layers "F.Cu" "F.Mask" "F.Paste")
			(net "Net_1506")
		)
		(pad "11" smd rect
			(at 2.8575 2.6162)
			(size 0.3556 1.524)
			(layers "F.Cu" "F.Mask" "F.Paste")
			(net "Net_1507")
		)
		(pad "12" smd rect
			(at 3.4925 2.6162)
			(size 0.3556 1.524)
			(layers "F.Cu" "F.Mask" "F.Paste")
			(net "GND")
		)
		(pad "13" smd rect
			(at 3.4925 -2.6162)
			(size 0.3556 1.524)
			(layers "F.Cu" "F.Mask" "F.Paste")
			(net "Net_1503")
		)
		(pad "14" smd rect
			(at 2.8575 -2.6162)
			(size 0.3556 1.524)
			(layers "F.Cu" "F.Mask" "F.Paste")
			(net "Net_1504")
		)
		(pad "15" smd rect
			(at 2.2225 -2.6162)
			(size 0.3556 1.524)
			(layers "F.Cu" "F.Mask" "F.Paste")
			(net "Net_1505")
		)
		(pad "16" smd rect
			(at 1.5875 -2.6162)
			(size 0.3556 1.524)
			(layers "F.Cu" "F.Mask" "F.Paste")
			(net "Net_1508")
		)
		(pad "17" smd rect
			(at 0.9525 -2.6162)
			(size 0.3556 1.524)
			(layers "F.Cu" "F.Mask" "F.Paste")
			(net "SAS_HDD_PWR15_PCIE")
		)
		(pad "18" smd rect
			(at 0.3175 -2.6162)
			(size 0.3556 1.524)
			(layers "F.Cu" "F.Mask" "F.Paste")
			(net "SAS_HDD_PWR14_PCIE")
		)
		(pad "19" smd rect
			(at -0.3175 -2.6162)
			(size 0.3556 1.524)
			(layers "F.Cu" "F.Mask" "F.Paste")
			(net "SAS_HDD_PWR13_PCIE")
		)
		(pad "20" smd rect
			(at -0.9525 -2.6162)
			(size 0.3556 1.524)
			(layers "F.Cu" "F.Mask" "F.Paste")
			(net "SAS_HDD_PWR12_PCIE")
		)
		(pad "21" smd rect
			(at -1.5875 -2.6162)
			(size 0.3556 1.524)
			(layers "F.Cu" "F.Mask" "F.Paste")
			(net "SAS_HDD_PWR11_PCIE")
		)
		(pad "22" smd rect
			(at -2.2225 -2.6162)
			(size 0.3556 1.524)
			(layers "F.Cu" "F.Mask" "F.Paste")
			(net "SAS_HDD_PWR10_PCIE")
		)
		(pad "23" smd rect
			(at -2.8575 -2.6162)
			(size 0.3556 1.524)
			(layers "F.Cu" "F.Mask" "F.Paste")
			(net "PCIE_MATED#_AB")
		)
		(pad "24" smd rect
			(at -3.4925 -2.6162)
			(size 0.3556 1.524)
			(layers "F.Cu" "F.Mask" "F.Paste")
			(net "P3V3_STBY")
		)
	)
	(footprint ""
		(layer "F.Cu")
		(at 139.07897 -92.583 180)
		(property "Reference" "TP170"
			(at 0 0 180)
			(layer "F.SilkS")
			(hide yes)
			(effects
				(font
					(size 1.27 1.27)
				)
			)
		)
		(property "Value" "TPAD32-GP"
			(at 0 -3.166364 180)
			(unlocked yes)
			(layer "F.Fab")
			(hide yes)
			(effects
				(font
					(size 1.016 1.016)
					(thickness 0.1524)
				)
			)
		)
		(property "Device Type" "TPAD32"
			(at 0 -4.690618 180)
			(unlocked yes)
			(layer "F.Fab")
			(hide yes)
			(effects
				(font
					(size 1.016 1.016)
					(thickness 0.1524)
				)
			)
		)
		(duplicate_pad_numbers_are_jumpers no)
		(fp_poly
			(pts
				(arc
					(start -0.4064 0)
					(mid 0.4064 0)
					(end -0.4064 0)
				)
			)
			(stroke
				(width 0)
				(type default)
			)
			(fill no)
			(layer "F.CrtYd")
		)
		(fp_poly
			(pts
				(arc
					(start -0.7112 0)
					(mid 0.7112 0)
					(end -0.7112 0)
				)
			)
			(stroke
				(width 0)
				(type default)
			)
			(fill no)
			(layer "F.Fab")
		)
		(pad "1" smd circle
			(at 0 0 180)
			(size 0.8128 0.8128)
			(layers "F.Cu" "F.Mask" "F.Paste")
			(net "TEMP_3_ALERT")
		)
	)
	(footprint ""
		(layer "F.Cu")
		(at 329.302872 -172.030136 -90)
		(property "Reference" "U27"
			(at 0 0 270)
			(layer "F.SilkS")
			(hide yes)
			(effects
				(font
					(size 1.27 1.27)
				)
			)
		)
		(property "Value" "TS5A23157DGSR-GP"
			(at 0 -11.1252 270)
			(unlocked yes)
			(layer "F.Fab")
			(hide yes)
			(effects
				(font
					(size 1.016 1.016)
					(thickness 0.1524)
				)
			)
		)
		(property "Device Type" "MSOP10H44"
			(at 0 -12.6492 270)
			(unlocked yes)
			(layer "F.Fab")
			(hide yes)
			(effects
				(font
					(size 1.016 1.016)
					(thickness 0.1524)
				)
			)
		)
		(duplicate_pad_numbers_are_jumpers no)
		(fp_line
			(start -2.0066 1.016)
			(end -2.0066 -1.016)
			(stroke
				(width 0.1524)
				(type default)
			)
			(layer "F.SilkS")
		)
		(fp_line
			(start -1.8288 1.016)
			(end -1.8288 3.048)
			(stroke
				(width 0.508)
				(type default)
			)
			(layer "F.SilkS")
		)
		(fp_line
			(start 1.143 1.016)
			(end -2.0066 1.016)
			(stroke
				(width 0.1524)
				(type default)
			)
			(layer "F.SilkS")
		)
		(fp_line
			(start -1.5748 0)
			(end -1.9558 0.381)
			(stroke
				(width 0.1524)
				(type default)
			)
			(layer "F.SilkS")
		)
		(fp_line
			(start -1.5748 0)
			(end -1.9558 -0.381)
			(stroke
				(width 0.1524)
				(type default)
			)
			(layer "F.SilkS")
		)
		(fp_line
			(start -2.0066 -1.016)
			(end 1.143 -1.016)
			(stroke
				(width 0.1524)
				(type default)
			)
			(layer "F.SilkS")
		)
		(fp_line
			(start 1.143 -1.016)
			(end 1.143 1.016)
			(stroke
				(width 0.1524)
				(type default)
			)
			(layer "F.SilkS")
		)
		(fp_poly
			(pts
				(xy -2.0828 3.3401) (xy 2.0828 3.3401) (xy 2.0828 -3.3401) (xy -2.0828 -3.3401)
			)
			(stroke
				(width 0)
				(type default)
			)
			(fill no)
			(layer "F.CrtYd")
		)
		(fp_poly
			(pts
				(xy -2.0828 3.3401) (xy 2.0828 3.3401) (xy 2.0828 -3.3401) (xy -2.0828 -3.3401)
			)
			(stroke
				(width 0)
				(type default)
			)
			(fill no)
			(layer "F.Fab")
		)
		(pad "1" smd rect
			(at -0.99949 2.0701 270)
			(size 0.3048 1.524)
			(layers "F.Cu" "F.Mask" "F.Paste")
			(net "BMC_UART_SWITCH_1R")
		)
		(pad "2" smd rect
			(at -0.50038 2.0701 270)
			(size 0.3048 1.524)
			(layers "F.Cu" "F.Mask" "F.Paste")
			(net "EXP_UART_TX_R")
		)
		(pad "3" smd rect
			(at 0 2.0701 270)
			(size 0.3048 1.524)
			(layers "F.Cu" "F.Mask" "F.Paste")
			(net "GND")
		)
		(pad "4" smd rect
			(at 0.50038 2.0701 270)
			(size 0.3048 1.524)
			(layers "F.Cu" "F.Mask" "F.Paste")
			(net "EXP_UART_RX_R")
		)
		(pad "5" smd rect
			(at 0.99949 2.0701 270)
			(size 0.3048 1.524)
			(layers "F.Cu" "F.Mask" "F.Paste")
			(net "BMC_UART_SWITCH_1R")
		)
		(pad "6" smd rect
			(at 0.99949 -2.0701 270)
			(size 0.3048 1.524)
			(layers "F.Cu" "F.Mask" "F.Paste")
			(net "UART2_RX")
		)
		(pad "7" smd rect
			(at 0.50038 -2.0701 270)
			(size 0.3048 1.524)
			(layers "F.Cu" "F.Mask" "F.Paste")
			(net "BMC_RXD5")
		)
		(pad "8" smd rect
			(at 0 -2.0701 270)
			(size 0.3048 1.524)
			(layers "F.Cu" "F.Mask" "F.Paste")
			(net "P3V3_STBY")
		)
		(pad "9" smd rect
			(at -0.50038 -2.0701 270)
			(size 0.3048 1.524)
			(layers "F.Cu" "F.Mask" "F.Paste")
			(net "BMC_TXD5")
		)
		(pad "10" smd rect
			(at -0.99949 -2.0701 270)
			(size 0.3048 1.524)
			(layers "F.Cu" "F.Mask" "F.Paste")
			(net "UART2_TX")
		)
	)
	(footprint ""
		(layer "F.Cu")
		(at 277.994872 -221.433136 90)
		(property "Reference" "PR82"
			(at 0 0 90)
			(layer "F.SilkS")
			(hide yes)
			(effects
				(font
					(size 1.27 1.27)
				)
			)
		)
		(property "Value" "2K7R2J-GP"
			(at 0.064008 -3.993896 90)
			(unlocked yes)
			(layer "F.Fab")
			(hide yes)
			(effects
				(font
					(size 1.016 1.016)
					(thickness 0.1524)
				)
			)
		)
		(property "Device Type" "R402H16"
			(at 0.064008 -5.517896 90)
			(unlocked yes)
			(layer "F.Fab")
			(hide yes)
			(effects
				(font
					(size 1.016 1.016)
					(thickness 0.1524)
				)
			)
		)
		(duplicate_pad_numbers_are_jumpers no)
		(fp_line
			(start 0.508 -0.9398)
			(end -0.508 -0.9398)
			(stroke
				(width 0.1524)
				(type default)
			)
			(layer "F.SilkS")
		)
		(fp_line
			(start -0.508 -0.9398)
			(end -0.508 0.9398)
			(stroke
				(width 0.1524)
				(type default)
			)
			(layer "F.SilkS")
		)
		(fp_rect
			(start -0.508 0.9398)
			(end 0.508 -0.9398)
			(stroke
				(width 0)
				(type default)
			)
			(fill no)
			(layer "F.CrtYd")
		)
		(fp_rect
			(start -0.508 0.9398)
			(end 0.508 -0.9398)
			(stroke
				(width 0)
				(type default)
			)
			(fill no)
			(layer "F.Fab")
		)
		(pad "1" smd custom
			(at 0 -0.4445 90)
			(size 0.1397 0.1397)
			(layers "F.Cu" "F.Mask" "F.Paste")
			(net "P3V3_STBY")
			(options
				(clearance outline)
				(anchor circle)
			)
			(primitives
				(gr_poly
					(pts
						(arc
							(start -0.1778 -0.2794)
							(mid -0.249642 -0.249642)
							(end -0.2794 -0.1778)
						)
						(arc
							(start -0.2794 0.1778)
							(mid -0.249642 0.249642)
							(end -0.1778 0.2794)
						)
						(arc
							(start 0.1778 0.2794)
							(mid 0.249642 0.249642)
							(end 0.2794 0.1778)
						)
						(arc
							(start 0.2794 -0.1778)
							(mid 0.249642 -0.249642)
							(end 0.1778 -0.2794)
						)
					)
					(width 0)
					(fill yes)
				)
			)
		)
		(pad "2" smd custom
			(at 0 0.4445 90)
			(size 0.1397 0.1397)
			(layers "F.Cu" "F.Mask" "F.Paste")
			(net "P1V53_STBY_PG")
			(options
				(clearance outline)
				(anchor circle)
			)
			(primitives
				(gr_poly
					(pts
						(arc
							(start -0.1778 -0.2794)
							(mid -0.249642 -0.249642)
							(end -0.2794 -0.1778)
						)
						(arc
							(start -0.2794 0.1778)
							(mid -0.249642 0.249642)
							(end -0.1778 0.2794)
						)
						(arc
							(start 0.1778 0.2794)
							(mid 0.249642 0.249642)
							(end 0.2794 0.1778)
						)
						(arc
							(start 0.2794 -0.1778)
							(mid 0.249642 -0.249642)
							(end 0.1778 -0.2794)
						)
					)
					(width 0)
					(fill yes)
				)
			)
		)
	)
	(footprint ""
		(layer "F.Cu")
		(at 87.992966 -80.137)
		(property "Reference" "SC1197"
			(at 0 0 0)
			(layer "F.SilkS")
			(hide yes)
			(effects
				(font
					(size 1.27 1.27)
				)
			)
		)
		(property "Value" "SCD1U6D3V1KX-GP"
			(at -2.8321 -1.7399 0)
			(unlocked yes)
			(layer "F.Fab")
			(hide yes)
			(effects
				(font
					(size 1.016 1.016)
					(thickness 0.1524)
				)
			)
		)
		(property "Device Type" "C0201H13"
			(at -2.8321 -3.2639 0)
			(unlocked yes)
			(layer "F.Fab")
			(hide yes)
			(effects
				(font
					(size 1.016 1.016)
					(thickness 0.1524)
				)
			)
		)
		(duplicate_pad_numbers_are_jumpers no)
		(fp_rect
			(start -0.2794 0.6477)
			(end 0.2794 -0.6477)
			(stroke
				(width 0)
				(type default)
			)
			(fill no)
			(layer "F.CrtYd")
		)
		(fp_rect
			(start -0.2794 0.6477)
			(end 0.2794 -0.6477)
			(stroke
				(width 0)
				(type default)
			)
			(fill no)
			(layer "F.Fab")
		)
		(pad "1" smd custom
			(at 0 -0.2794)
			(size 0.0762 0.0762)
			(layers "F.Cu" "F.Mask" "F.Paste")
			(net "XTAL_VDDA09")
			(options
				(clearance outline)
				(anchor circle)
			)
			(primitives
				(gr_poly
					(pts
						(arc
							(start 0.1524 -0.127)
							(mid 0.137521 -0.162921)
							(end 0.1016 -0.1778)
						)
						(arc
							(start -0.1016 -0.1778)
							(mid -0.137521 -0.162921)
							(end -0.1524 -0.127)
						)
						(arc
							(start -0.1524 0.127)
							(mid -0.137521 0.162921)
							(end -0.1016 0.1778)
						)
						(arc
							(start 0.1016 0.1778)
							(mid 0.137521 0.162921)
							(end 0.1524 0.127)
						)
					)
					(width 0)
					(fill yes)
				)
			)
		)
		(pad "2" smd custom
			(at 0 0.2794)
			(size 0.0762 0.0762)
			(layers "F.Cu" "F.Mask" "F.Paste")
			(net "GND")
			(options
				(clearance outline)
				(anchor circle)
			)
			(primitives
				(gr_poly
					(pts
						(arc
							(start 0.1524 -0.127)
							(mid 0.137521 -0.162921)
							(end 0.1016 -0.1778)
						)
						(arc
							(start -0.1016 -0.1778)
							(mid -0.137521 -0.162921)
							(end -0.1524 -0.127)
						)
						(arc
							(start -0.1524 0.127)
							(mid -0.137521 0.162921)
							(end -0.1016 0.1778)
						)
						(arc
							(start 0.1016 0.1778)
							(mid 0.137521 0.162921)
							(end 0.1524 0.127)
						)
					)
					(width 0)
					(fill yes)
				)
			)
		)
	)
	(footprint ""
		(layer "F.Cu")
		(at 174.117 -129.921 90)
		(property "Reference" "PC173"
			(at 0 0 90)
			(layer "F.SilkS")
			(hide yes)
			(effects
				(font
					(size 1.27 1.27)
				)
			)
		)
		(property "Value" "SC22U25V5MX-GP"
			(at -0.0762 -6.1214 90)
			(unlocked yes)
			(layer "F.Fab")
			(hide yes)
			(effects
				(font
					(size 1.016 1.016)
					(thickness 0.1524)
				)
			)
		)
		(property "Device Type" "C805H58"
			(at -0.0762 -8.1534 90)
			(unlocked yes)
			(layer "F.Fab")
			(hide yes)
			(effects
				(font
					(size 1.016 1.016)
					(thickness 0.1524)
				)
			)
		)
		(duplicate_pad_numbers_are_jumpers no)
		(fp_line
			(start 0.635 0)
			(end -0.635 0)
			(stroke
				(width 0.508)
				(type default)
			)
			(layer "F.SilkS")
		)
		(fp_rect
			(start -0.9652 1.778)
			(end 0.9652 -1.778)
			(stroke
				(width 0)
				(type default)
			)
			(fill no)
			(layer "F.CrtYd")
		)
		(fp_poly
			(pts
				(xy -0.9652 -1.778) (xy 0.9652 -1.778) (xy 0.9652 1.778) (xy -0.9652 1.778)
			)
			(stroke
				(width 0)
				(type default)
			)
			(fill no)
			(layer "F.Fab")
		)
		(pad "1" smd rect
			(at 0 -0.9652 90)
			(size 1.397 1.143)
			(layers "F.Cu" "F.Mask" "F.Paste")
			(net "P0V9_E_VIN")
		)
		(pad "2" smd rect
			(at 0 0.9652 90)
			(size 1.397 1.143)
			(layers "F.Cu" "F.Mask" "F.Paste")
			(net "GND")
		)
	)
)
